# SCM (Grand Teton) — schematic netlist excerpt (pin names and nets, part order shuffled) for the footprints in the layout excerpt that follows; sources: Cadence DE-HDL packaged netlist, KiCad conversion of 12092022_DA0F0TMDCD0_F0T_Management_Board_D_brd_V3_OCP.brd

C127  Q_CAP  1UF 25V 10% X6S  pkg C0402  page 16 : A = P1V2_AUX ; B = GND
R754  Q_RES  4.7K 1% EMPTY  pkg 0402LF  page 27 : A = P3V3_RGM ; B = UART_BMC_5_TXD_R

(kicad_pcb
	(version 20260206)
	(generator "pcbnew")
	(generator_version "10.0")
	(general
		(thickness 1.6)
		(legacy_teardrops no)
	)
	(paper "A4")
	(title_block
		(title "12092022_DA0F0TMDCD0_F0T_Management_Board_D_brd_V3_OCP.brd")
		(comment 1 "Grand Teton / footprints 1088-1089 of 1440")
	)
	(layers
		(0 "F.Cu" signal "TOP")
		(4 "In1.Cu" signal "GND")
		(6 "In2.Cu" signal "IN1")
		(8 "In3.Cu" signal "GND1")
		(10 "In4.Cu" signal "IN2")
		(12 "In5.Cu" signal "VCC")
		(14 "In6.Cu" signal "VCC1")
		(16 "In7.Cu" signal "IN3")
		(18 "In8.Cu" signal "GND2")
		(20 "In9.Cu" signal "IN4")
		(22 "In10.Cu" signal "GND3")
		(2 "B.Cu" signal "BOTTOM")
		(9 "F.Adhes" user "F.Adhesive")
		(11 "B.Adhes" user "B.Adhesive")
		(13 "F.Paste" user "Package Geometry/Pastemask Top")
		(15 "B.Paste" user "Package Geometry/Pastemask Bottom")
		(5 "F.SilkS" user "Ref Des/Silkscreen Top")
		(7 "B.SilkS" user "Ref Des/Silkscreen Bottom")
		(1 "F.Mask" user "Board Geometry/Soldermask Top")
		(3 "B.Mask" user "Board Geometry/Soldermask Bottom")
		(17 "Dwgs.User" user "User.Drawings")
		(19 "Cmts.User" user "User.Comments")
		(21 "Eco1.User" user "User.Eco1")
		(23 "Eco2.User" user "User.Eco2")
		(25 "Edge.Cuts" user "Board Geometry/Outline")
		(27 "Margin" user)
		(31 "F.CrtYd" user "Package Geometry/Place Bound Top")
		(29 "B.CrtYd" user "Package Geometry/Place Bound Bottom")
		(35 "F.Fab" user "Ref Des/Assembly Top")
		(33 "B.Fab" user "Ref Des/Assembly Bottom")
	)
	(footprint ""
		(layer "B.Cu")
		(at 71.73976 -37.271706 -90)
		(property "Reference" "C127"
			(at 0 0 90)
			(layer "B.SilkS")
			(hide yes)
			(effects
				(font
					(size 1.27 1.27)
				)
				(justify mirror)
			)
		)
		(property "Value" ""
			(at 0 0 90)
			(layer "B.Fab")
			(effects
				(font
					(size 1.27 1.27)
				)
				(justify mirror)
			)
		)
		(duplicate_pad_numbers_are_jumpers no)
		(fp_line
			(start -0.7874 0.4064)
			(end 0.7874 0.4064)
			(stroke
				(width 0.1524)
				(type default)
			)
			(layer "B.SilkS")
		)
		(fp_line
			(start 0.7874 0.4064)
			(end 0.7874 -0.4064)
			(stroke
				(width 0.1524)
				(type default)
			)
			(layer "B.SilkS")
		)
		(fp_line
			(start -0.7874 -0.4064)
			(end -0.7874 0.4064)
			(stroke
				(width 0.1524)
				(type default)
			)
			(layer "B.SilkS")
		)
		(fp_line
			(start 0.7874 -0.4064)
			(end -0.7874 -0.4064)
			(stroke
				(width 0.1524)
				(type default)
			)
			(layer "B.SilkS")
		)
		(fp_line
			(start -0.67945 0.3048)
			(end -0.120396 0.3048)
			(stroke
				(width 0.1)
				(type default)
			)
			(layer "B.Fab")
		)
		(fp_line
			(start -0.120396 0.3048)
			(end -0.120396 0.2794)
			(stroke
				(width 0.1)
				(type default)
			)
			(layer "B.Fab")
		)
		(fp_line
			(start 0.12065 0.3048)
			(end 0.67945 0.3048)
			(stroke
				(width 0.1)
				(type default)
			)
			(layer "B.Fab")
		)
		(fp_line
			(start 0.67945 0.3048)
			(end 0.67945 -0.305054)
			(stroke
				(width 0.1)
				(type default)
			)
			(layer "B.Fab")
		)
		(fp_line
			(start -0.120396 0.2794)
			(end 0.12065 0.2794)
			(stroke
				(width 0.1)
				(type default)
			)
			(layer "B.Fab")
		)
		(fp_line
			(start 0.12065 0.2794)
			(end 0.12065 0.3048)
			(stroke
				(width 0.1)
				(type default)
			)
			(layer "B.Fab")
		)
		(fp_line
			(start -0.12065 -0.2794)
			(end -0.12065 -0.3048)
			(stroke
				(width 0.1)
				(type default)
			)
			(layer "B.Fab")
		)
		(fp_line
			(start 0.12065 -0.2794)
			(end -0.12065 -0.2794)
			(stroke
				(width 0.1)
				(type default)
			)
			(layer "B.Fab")
		)
		(fp_line
			(start -0.67945 -0.3048)
			(end -0.67945 0.3048)
			(stroke
				(width 0.1)
				(type default)
			)
			(layer "B.Fab")
		)
		(fp_line
			(start -0.12065 -0.3048)
			(end -0.67945 -0.3048)
			(stroke
				(width 0.1)
				(type default)
			)
			(layer "B.Fab")
		)
		(fp_line
			(start 0.12065 -0.305054)
			(end 0.12065 -0.2794)
			(stroke
				(width 0.1)
				(type default)
			)
			(layer "B.Fab")
		)
		(fp_line
			(start 0.67945 -0.305054)
			(end 0.12065 -0.305054)
			(stroke
				(width 0.1)
				(type default)
			)
			(layer "B.Fab")
		)
		(pad "1" smd circle
			(at 0.40005 0 90)
			(size 0 0)
			(layers "B.Cu" "B.Mask" "B.Paste")
			(net "P1V2_AUX")
		)
		(pad "2" smd circle
			(at -0.40005 0 90)
			(size 0 0)
			(layers "B.Cu" "B.Mask" "B.Paste")
			(net "GND")
		)
	)
	(footprint ""
		(layer "B.Cu")
		(at 45.212 -86.44255 90)
		(property "Reference" "R754"
			(at 0 0 90)
			(layer "B.SilkS")
			(hide yes)
			(effects
				(font
					(size 1.27 1.27)
				)
				(justify mirror)
			)
		)
		(property "Value" ""
			(at 0 0 90)
			(layer "B.Fab")
			(effects
				(font
					(size 1.27 1.27)
				)
				(justify mirror)
			)
		)
		(duplicate_pad_numbers_are_jumpers no)
		(fp_line
			(start 0.7874 -0.4064)
			(end -0.7874 -0.4064)
			(stroke
				(width 0.1524)
				(type default)
			)
			(layer "B.SilkS")
		)
		(fp_line
			(start -0.7874 -0.4064)
			(end -0.7874 0.4064)
			(stroke
				(width 0.1524)
				(type default)
			)
			(layer "B.SilkS")
		)
		(fp_line
			(start 0.7874 0.4064)
			(end 0.7874 -0.4064)
			(stroke
				(width 0.1524)
				(type default)
			)
			(layer "B.SilkS")
		)
		(fp_line
			(start -0.7874 0.4064)
			(end 0.7874 0.4064)
			(stroke
				(width 0.1524)
				(type default)
			)
			(layer "B.SilkS")
		)
		(fp_line
			(start 0.67945 -0.305054)
			(end 0.12065 -0.305054)
			(stroke
				(width 0.1)
				(type default)
			)
			(layer "B.Fab")
		)
		(fp_line
			(start 0.12065 -0.305054)
			(end 0.12065 -0.2794)
			(stroke
				(width 0.1)
				(type default)
			)
			(layer "B.Fab")
		)
		(fp_line
			(start -0.12065 -0.3048)
			(end -0.67945 -0.3048)
			(stroke
				(width 0.1)
				(type default)
			)
			(layer "B.Fab")
		)
		(fp_line
			(start -0.67945 -0.3048)
			(end -0.67945 0.3048)
			(stroke
				(width 0.1)
				(type default)
			)
			(layer "B.Fab")
		)
		(fp_line
			(start 0.12065 -0.2794)
			(end -0.12065 -0.2794)
			(stroke
				(width 0.1)
				(type default)
			)
			(layer "B.Fab")
		)
		(fp_line
			(start -0.12065 -0.2794)
			(end -0.12065 -0.3048)
			(stroke
				(width 0.1)
				(type default)
			)
			(layer "B.Fab")
		)
		(fp_line
			(start 0.12065 0.2794)
			(end 0.12065 0.3048)
			(stroke
				(width 0.1)
				(type default)
			)
			(layer "B.Fab")
		)
		(fp_line
			(start -0.120396 0.2794)
			(end 0.12065 0.2794)
			(stroke
				(width 0.1)
				(type default)
			)
			(layer "B.Fab")
		)
		(fp_line
			(start 0.67945 0.3048)
			(end 0.67945 -0.305054)
			(stroke
				(width 0.1)
				(type default)
			)
			(layer "B.Fab")
		)
		(fp_line
			(start 0.12065 0.3048)
			(end 0.67945 0.3048)
			(stroke
				(width 0.1)
				(type default)
			)
			(layer "B.Fab")
		)
		(fp_line
			(start -0.120396 0.3048)
			(end -0.120396 0.2794)
			(stroke
				(width 0.1)
				(type default)
			)
			(layer "B.Fab")
		)
		(fp_line
			(start -0.67945 0.3048)
			(end -0.120396 0.3048)
			(stroke
				(width 0.1)
				(type default)
			)
			(layer "B.Fab")
		)
		(pad "1" smd circle
			(at 0.40005 0 270)
			(size 0 0)
			(layers "B.Cu" "B.Mask" "B.Paste")
			(net "P3V3_RGM")
		)
		(pad "2" smd circle
			(at -0.40005 0 270)
			(size 0 0)
			(layers "B.Cu" "B.Mask" "B.Paste")
			(net "UART_BMC_5_TXD_R")
		)
	)
)
